(kicad_pcb
	(version 20260206)
	(generator "pcbnew")
	(generator_version "10.0")
	(general
		(thickness 1.6)
		(legacy_teardrops no)
	)
	(paper "A4")
	(title_block
		(title "Wiwynn_Tioga_Pass_MB.brd")
		(comment 1 "Tioga Pass / footprints 2000-2006 of 4770")
	)
	(layers
		(0 "F.Cu" signal "TOP")
		(4 "In1.Cu" signal "L2GND")
		(6 "In2.Cu" signal "L3")
		(8 "In3.Cu" signal "L4GND")
		(10 "In4.Cu" signal "L5")
		(12 "In5.Cu" signal "L6GND")
		(14 "In6.Cu" signal "L7VCC")
		(16 "In7.Cu" signal "L8VCC")
		(18 "In8.Cu" signal "L9GND")
		(20 "In9.Cu" signal "L10")
		(22 "In10.Cu" signal "L11GND")
		(24 "In11.Cu" signal "L12")
		(26 "In12.Cu" signal "L13GND")
		(2 "B.Cu" signal "BOTTOM")
		(9 "F.Adhes" user "F.Adhesive")
		(11 "B.Adhes" user "B.Adhesive")
		(13 "F.Paste" user "Package Geometry/Pastemask Top")
		(15 "B.Paste" user "Package Geometry/Pastemask Bottom")
		(5 "F.SilkS" user "Ref Des/Silkscreen Top")
		(7 "B.SilkS" user "Ref Des/Silkscreen Bottom")
		(1 "F.Mask" user "Board Geometry/Soldermask Top")
		(3 "B.Mask" user "Board Geometry/Soldermask Bottom")
		(17 "Dwgs.User" user "User.Drawings")
		(19 "Cmts.User" user "User.Comments")
		(21 "Eco1.User" user "User.Eco1")
		(23 "Eco2.User" user "User.Eco2")
		(25 "Edge.Cuts" user "Board Geometry/Outline")
		(27 "Margin" user)
		(31 "F.CrtYd" user "Package Geometry/Place Bound Top")
		(29 "B.CrtYd" user "Package Geometry/Place Bound Bottom")
		(35 "F.Fab" user "Ref Des/Assembly Top")
		(33 "B.Fab" user "Ref Des/Assembly Bottom")
	)
	(footprint ""
		(layer "F.Cu")
		(at 344.0176 -141.224 90)
		(property "Reference" "RT32"
			(at 0 0 90)
			(layer "F.SilkS")
			(hide yes)
			(effects
				(font
					(size 1.27 1.27)
				)
			)
		)
		(property "Value" "*"
			(at -0.0254 -2.6289 90)
			(unlocked yes)
			(layer "F.Fab")
			(hide yes)
			(effects
				(font
					(size 1.27 1.016)
					(thickness 0.1524)
				)
			)
		)
		(property "Device Type" "1R3F-GP_RCL_GP-1R3F-GP,64.1R00A"
			(at -0.0254 -4.1529 90)
			(unlocked yes)
			(layer "F.Fab")
			(hide yes)
			(effects
				(font
					(size 1.27 1.016)
					(thickness 0.1524)
				)
			)
		)
		(duplicate_pad_numbers_are_jumpers no)
		(fp_line
			(start 0.2032 0)
			(end 0.4826 0)
			(stroke
				(width 0.2032)
				(type default)
			)
			(layer "F.SilkS")
		)
		(fp_line
			(start -0.4826 0)
			(end -0.2032 0)
			(stroke
				(width 0.2032)
				(type default)
			)
			(layer "F.SilkS")
		)
		(fp_rect
			(start -0.5842 1.3335)
			(end 0.5842 -1.3335)
			(stroke
				(width 0)
				(type default)
			)
			(fill no)
			(layer "F.CrtYd")
		)
		(fp_rect
			(start -0.5842 1.3335)
			(end 0.5842 -1.3335)
			(stroke
				(width 0)
				(type default)
			)
			(fill no)
			(layer "F.Fab")
		)
		(pad "1" smd custom
			(at 0 -0.762 90)
			(size 0.2159 0.2159)
			(layers "F.Cu" "F.Mask" "F.Paste")
			(net "VR_PVDDQ_DEF_PH2_SW_RC")
			(options
				(clearance outline)
				(anchor circle)
			)
			(primitives
				(gr_poly
					(pts
						(arc
							(start -0.3302 -0.4318)
							(mid -0.402042 -0.402042)
							(end -0.4318 -0.3302)
						)
						(arc
							(start -0.4318 0.3302)
							(mid -0.402042 0.402042)
							(end -0.3302 0.4318)
						)
						(arc
							(start 0.3302 0.4318)
							(mid 0.402042 0.402042)
							(end 0.4318 0.3302)
						)
						(arc
							(start 0.4318 -0.3302)
							(mid 0.402042 -0.402042)
							(end 0.3302 -0.4318)
						)
					)
					(width 0)
					(fill yes)
				)
			)
		)
		(pad "2" smd custom
			(at 0 0.762 90)
			(size 0.2159 0.2159)
			(layers "F.Cu" "F.Mask" "F.Paste")
			(net "GND")
			(options
				(clearance outline)
				(anchor circle)
			)
			(primitives
				(gr_poly
					(pts
						(arc
							(start -0.3302 -0.4318)
							(mid -0.402042 -0.402042)
							(end -0.4318 -0.3302)
						)
						(arc
							(start -0.4318 0.3302)
							(mid -0.402042 0.402042)
							(end -0.3302 0.4318)
						)
						(arc
							(start 0.3302 0.4318)
							(mid 0.402042 0.402042)
							(end 0.4318 0.3302)
						)
						(arc
							(start 0.4318 -0.3302)
							(mid 0.402042 -0.402042)
							(end 0.3302 -0.4318)
						)
					)
					(width 0)
					(fill yes)
				)
			)
		)
	)
	(footprint ""
		(layer "F.Cu")
		(at 8.4074 -138.2014)
		(property "Reference" "L1A2"
			(at 3.378708 -4.251706 0)
			(unlocked yes)
			(layer "F.SilkS")
			(effects
				(font
					(size 0.4064 0.254)
					(thickness 0.1524)
				)
			)
		)
		(property "Value" ""
			(at 0 0 0)
			(layer "F.Fab")
			(effects
				(font
					(size 1.27 1.27)
				)
			)
		)
		(duplicate_pad_numbers_are_jumpers no)
		(fp_line
			(start -1.1303 -3.199892)
			(end 8.3693 -3.199892)
			(stroke
				(width 0.1524)
				(type default)
			)
			(layer "F.SilkS")
		)
		(fp_line
			(start -1.1303 -1.6637)
			(end -1.1303 -3.199892)
			(stroke
				(width 0.1524)
				(type default)
			)
			(layer "F.SilkS")
		)
		(fp_line
			(start -1.1303 3.199892)
			(end -1.1303 1.6637)
			(stroke
				(width 0.1524)
				(type default)
			)
			(layer "F.SilkS")
		)
		(fp_line
			(start 8.3693 -3.199892)
			(end 8.3693 -1.6637)
			(stroke
				(width 0.1524)
				(type default)
			)
			(layer "F.SilkS")
		)
		(fp_line
			(start 8.3693 1.6637)
			(end 8.3693 3.199892)
			(stroke
				(width 0.1524)
				(type default)
			)
			(layer "F.SilkS")
		)
		(fp_line
			(start 8.3693 3.199892)
			(end -1.1303 3.199892)
			(stroke
				(width 0.1524)
				(type default)
			)
			(layer "F.SilkS")
		)
		(fp_rect
			(start -1.1303 3.199892)
			(end 8.3693 -3.199892)
			(stroke
				(width 0)
				(type default)
			)
			(fill no)
			(layer "F.CrtYd")
		)
		(fp_line
			(start -1.1303 -3.199892)
			(end 8.3693 -3.199892)
			(stroke
				(width 0.1)
				(type default)
			)
			(layer "F.Fab")
		)
		(fp_line
			(start -1.1303 3.199892)
			(end -1.1303 -3.199892)
			(stroke
				(width 0.1)
				(type default)
			)
			(layer "F.Fab")
		)
		(fp_line
			(start 8.3693 -3.199892)
			(end 8.3693 3.199892)
			(stroke
				(width 0.1)
				(type default)
			)
			(layer "F.Fab")
		)
		(fp_line
			(start 8.3693 3.199892)
			(end -1.1303 3.199892)
			(stroke
				(width 0.1)
				(type default)
			)
			(layer "F.Fab")
		)
		(pad "1" smd rect
			(at 0 0)
			(size 3.683 2.667)
			(layers "F.Cu" "F.Mask" "F.Paste")
			(net "VR_PVDDQ_KLM_PH1_SW")
		)
		(pad "2" smd rect
			(at 7.239 0)
			(size 3.683 2.667)
			(layers "F.Cu" "F.Mask" "F.Paste")
			(net "PVDDQ_KLM")
		)
	)
	(footprint ""
		(layer "F.Cu")
		(at 480.842574 4.65709 -90)
		(property "Reference" "R9G18"
			(at 0 0 270)
			(layer "F.SilkS")
			(hide yes)
			(effects
				(font
					(size 1.27 1.27)
				)
			)
		)
		(property "Value" ""
			(at 0 0 270)
			(layer "F.Fab")
			(effects
				(font
					(size 1.27 1.27)
				)
			)
		)
		(duplicate_pad_numbers_are_jumpers no)
		(fp_poly
			(pts
				(xy -0.2794 -0.1016) (xy 0.2794 -0.1016) (xy 0.2794 0.9906) (xy -0.2794 0.9906)
			)
			(stroke
				(width 0)
				(type default)
			)
			(fill no)
			(layer "F.CrtYd")
		)
		(fp_line
			(start -0.2794 0.9906)
			(end 0.2794 0.9906)
			(stroke
				(width 0.1)
				(type default)
			)
			(layer "F.Fab")
		)
		(fp_line
			(start 0.2794 0.9906)
			(end 0.2794 -0.1016)
			(stroke
				(width 0.1)
				(type default)
			)
			(layer "F.Fab")
		)
		(fp_line
			(start -0.2794 -0.1016)
			(end -0.2794 0.9906)
			(stroke
				(width 0.1)
				(type default)
			)
			(layer "F.Fab")
		)
		(fp_line
			(start 0.2794 -0.1016)
			(end -0.2794 -0.1016)
			(stroke
				(width 0.1)
				(type default)
			)
			(layer "F.Fab")
		)
		(pad "1" smd rect
			(at 0 0 270)
			(size 0.508 0.508)
			(layers "F.Cu" "F.Mask" "F.Paste")
			(net "NIC_SET_P_MDI_2_DP")
		)
		(pad "2" smd rect
			(at 0 0.889 270)
			(size 0.508 0.508)
			(layers "F.Cu" "F.Mask" "F.Paste")
			(net "NIC_MDI_SPRV_RJ45_2_R_DP")
		)
		(zone
			(layer "F.Cu")
			(hatch none 0.5)
			(connect_pads
				(clearance 0)
			)
			(min_thickness 0.25)
			(keepout
				(tracks not_allowed)
				(vias allowed)
				(pads allowed)
				(copperpour not_allowed)
				(footprints allowed)
			)
			(placement
				(enabled no)
				(sheetname "")
			)
			(fill
				(thermal_gap 0.5)
				(thermal_bridge_width 0.5)
				(island_removal_mode 0)
			)
			(polygon
				(pts
					(xy 480.207574 4.40309) (xy 480.207574 4.91109) (xy 480.588574 4.91109) (xy 480.588574 4.40309)
				)
			)
		)
		(zone
			(layer "F.Cu")
			(hatch none 0.5)
			(connect_pads
				(clearance 0)
			)
			(min_thickness 0.25)
			(keepout
				(tracks allowed)
				(vias not_allowed)
				(pads allowed)
				(copperpour not_allowed)
				(footprints allowed)
			)
			(placement
				(enabled no)
				(sheetname "")
			)
			(fill
				(thermal_gap 0.5)
				(thermal_bridge_width 0.5)
				(island_removal_mode 0)
			)
			(polygon
				(pts
					(xy 480.588574 4.40309) (xy 480.588574 4.91109) (xy 480.207574 4.91109) (xy 480.207574 4.40309)
				)
			)
		)
	)
	(footprint ""
		(layer "F.Cu")
		(at 391.795 -151.236426)
		(property "Reference" "C8A8"
			(at 0 0 0)
			(layer "F.SilkS")
			(hide yes)
			(effects
				(font
					(size 1.27 1.27)
				)
			)
		)
		(property "Value" ""
			(at 0 0 0)
			(layer "F.Fab")
			(effects
				(font
					(size 1.27 1.27)
				)
			)
		)
		(duplicate_pad_numbers_are_jumpers no)
		(fp_poly
			(pts
				(xy 0.3048 -0.1016) (xy 0.3048 0.9906) (xy -0.3048 0.9906) (xy -0.3048 -0.1016)
			)
			(stroke
				(width 0)
				(type default)
			)
			(fill no)
			(layer "F.CrtYd")
		)
		(fp_line
			(start -0.3048 -0.1016)
			(end -0.3048 0.9906)
			(stroke
				(width 0.1)
				(type default)
			)
			(layer "F.Fab")
		)
		(fp_line
			(start -0.3048 0.9906)
			(end 0.3048 0.9906)
			(stroke
				(width 0.1)
				(type default)
			)
			(layer "F.Fab")
		)
		(fp_line
			(start 0.3048 -0.1016)
			(end -0.3048 -0.1016)
			(stroke
				(width 0.1)
				(type default)
			)
			(layer "F.Fab")
		)
		(fp_line
			(start 0.3048 0.9906)
			(end 0.3048 -0.1016)
			(stroke
				(width 0.1)
				(type default)
			)
			(layer "F.Fab")
		)
		(pad "1" smd rect
			(at 0 0)
			(size 0.508 0.508)
			(layers "F.Cu" "F.Mask" "F.Paste")
			(net "VR_PVNN_P1V05_PCH_VD12")
		)
		(pad "2" smd rect
			(at 0 0.889)
			(size 0.508 0.508)
			(layers "F.Cu" "F.Mask" "F.Paste")
			(net "GND")
		)
		(zone
			(layer "F.Cu")
			(hatch none 0.5)
			(connect_pads
				(clearance 0)
			)
			(min_thickness 0.25)
			(keepout
				(tracks allowed)
				(vias not_allowed)
				(pads allowed)
				(copperpour not_allowed)
				(footprints allowed)
			)
			(placement
				(enabled no)
				(sheetname "")
			)
			(fill
				(thermal_gap 0.5)
				(thermal_bridge_width 0.5)
				(island_removal_mode 0)
			)
			(polygon
				(pts
					(xy 391.541 -150.982426) (xy 392.049 -150.982426) (xy 392.049 -150.601426) (xy 391.541 -150.601426)
				)
			)
		)
		(zone
			(layer "F.Cu")
			(hatch none 0.5)
			(connect_pads
				(clearance 0)
			)
			(min_thickness 0.25)
			(keepout
				(tracks not_allowed)
				(vias allowed)
				(pads allowed)
				(copperpour not_allowed)
				(footprints allowed)
			)
			(placement
				(enabled no)
				(sheetname "")
			)
			(fill
				(thermal_gap 0.5)
				(thermal_bridge_width 0.5)
				(island_removal_mode 0)
			)
			(polygon
				(pts
					(xy 391.541 -150.601426) (xy 392.049 -150.601426) (xy 392.049 -150.982426) (xy 391.541 -150.982426)
				)
			)
		)
	)
	(footprint ""
		(layer "F.Cu")
		(at 351.1804 -94.685104 90)
		(property "Reference" "C7C12"
			(at 0 0 90)
			(layer "F.SilkS")
			(hide yes)
			(effects
				(font
					(size 1.27 1.27)
				)
			)
		)
		(property "Value" ""
			(at 0 0 90)
			(layer "F.Fab")
			(effects
				(font
					(size 1.27 1.27)
				)
			)
		)
		(duplicate_pad_numbers_are_jumpers no)
		(fp_poly
			(pts
				(xy 0.3048 -0.1016) (xy 0.3048 0.9906) (xy -0.3048 0.9906) (xy -0.3048 -0.1016)
			)
			(stroke
				(width 0)
				(type default)
			)
			(fill no)
			(layer "F.CrtYd")
		)
		(fp_line
			(start 0.3048 -0.1016)
			(end -0.3048 -0.1016)
			(stroke
				(width 0.1)
				(type default)
			)
			(layer "F.Fab")
		)
		(fp_line
			(start -0.3048 -0.1016)
			(end -0.3048 0.9906)
			(stroke
				(width 0.1)
				(type default)
			)
			(layer "F.Fab")
		)
		(fp_line
			(start 0.3048 0.9906)
			(end 0.3048 -0.1016)
			(stroke
				(width 0.1)
				(type default)
			)
			(layer "F.Fab")
		)
		(fp_line
			(start -0.3048 0.9906)
			(end 0.3048 0.9906)
			(stroke
				(width 0.1)
				(type default)
			)
			(layer "F.Fab")
		)
		(pad "1" smd rect
			(at 0 0 90)
			(size 0.508 0.508)
			(layers "F.Cu" "F.Mask" "F.Paste")
			(net "VR_FET_SW_P12V_STBY_PVCCIO_CPU0")
		)
		(pad "2" smd rect
			(at 0 0.889 90)
			(size 0.508 0.508)
			(layers "F.Cu" "F.Mask" "F.Paste")
			(net "GND")
		)
		(zone
			(layer "F.Cu")
			(hatch none 0.5)
			(connect_pads
				(clearance 0)
			)
			(min_thickness 0.25)
			(keepout
				(tracks allowed)
				(vias not_allowed)
				(pads allowed)
				(copperpour not_allowed)
				(footprints allowed)
			)
			(placement
				(enabled no)
				(sheetname "")
			)
			(fill
				(thermal_gap 0.5)
				(thermal_bridge_width 0.5)
				(island_removal_mode 0)
			)
			(polygon
				(pts
					(xy 351.4344 -94.431104) (xy 351.4344 -94.939104) (xy 351.8154 -94.939104) (xy 351.8154 -94.431104)
				)
			)
		)
		(zone
			(layer "F.Cu")
			(hatch none 0.5)
			(connect_pads
				(clearance 0)
			)
			(min_thickness 0.25)
			(keepout
				(tracks not_allowed)
				(vias allowed)
				(pads allowed)
				(copperpour not_allowed)
				(footprints allowed)
			)
			(placement
				(enabled no)
				(sheetname "")
			)
			(fill
				(thermal_gap 0.5)
				(thermal_bridge_width 0.5)
				(island_removal_mode 0)
			)
			(polygon
				(pts
					(xy 351.8154 -94.431104) (xy 351.8154 -94.939104) (xy 351.4344 -94.939104) (xy 351.4344 -94.431104)
				)
			)
		)
	)
	(footprint ""
		(layer "F.Cu")
		(at 385.29514 -82.28076 180)
		(property "Reference" "R7W14"
			(at -0.8382 -0.67818 180)
			(unlocked yes)
			(layer "F.SilkS")
			(effects
				(font
					(size 0.4064 0.254)
					(thickness 0.1524)
				)
				(justify left)
			)
		)
		(property "Value" ""
			(at 0 0 180)
			(layer "F.Fab")
			(effects
				(font
					(size 1.27 1.27)
				)
			)
		)
		(duplicate_pad_numbers_are_jumpers no)
		(fp_poly
			(pts
				(xy -0.2794 -0.1016) (xy 0.2794 -0.1016) (xy 0.2794 0.9906) (xy -0.2794 0.9906)
			)
			(stroke
				(width 0)
				(type default)
			)
			(fill no)
			(layer "F.CrtYd")
		)
		(fp_line
			(start 0.2794 0.9906)
			(end 0.2794 -0.1016)
			(stroke
				(width 0.1)
				(type default)
			)
			(layer "F.Fab")
		)
		(fp_line
			(start 0.2794 -0.1016)
			(end -0.2794 -0.1016)
			(stroke
				(width 0.1)
				(type default)
			)
			(layer "F.Fab")
		)
		(fp_line
			(start -0.2794 0.9906)
			(end 0.2794 0.9906)
			(stroke
				(width 0.1)
				(type default)
			)
			(layer "F.Fab")
		)
		(fp_line
			(start -0.2794 -0.1016)
			(end -0.2794 0.9906)
			(stroke
				(width 0.1)
				(type default)
			)
			(layer "F.Fab")
		)
		(pad "1" smd rect
			(at 0 0 180)
			(size 0.508 0.508)
			(layers "F.Cu" "F.Mask" "F.Paste")
			(net "FM_BMC_READY_N")
		)
		(pad "2" smd rect
			(at 0 0.889 180)
			(size 0.508 0.508)
			(layers "F.Cu" "F.Mask" "F.Paste")
			(net "FM_BMC_READY_R1_N")
		)
		(zone
			(layer "F.Cu")
			(hatch none 0.5)
			(connect_pads
				(clearance 0)
			)
			(min_thickness 0.25)
			(keepout
				(tracks not_allowed)
				(vias allowed)
				(pads allowed)
				(copperpour not_allowed)
				(footprints allowed)
			)
			(placement
				(enabled no)
				(sheetname "")
			)
			(fill
				(thermal_gap 0.5)
				(thermal_bridge_width 0.5)
				(island_removal_mode 0)
			)
			(polygon
				(pts
					(xy 385.54914 -82.91576) (xy 385.04114 -82.91576) (xy 385.04114 -82.53476) (xy 385.54914 -82.53476)
				)
			)
		)
		(zone
			(layer "F.Cu")
			(hatch none 0.5)
			(connect_pads
				(clearance 0)
			)
			(min_thickness 0.25)
			(keepout
				(tracks allowed)
				(vias not_allowed)
				(pads allowed)
				(copperpour not_allowed)
				(footprints allowed)
			)
			(placement
				(enabled no)
				(sheetname "")
			)
			(fill
				(thermal_gap 0.5)
				(thermal_bridge_width 0.5)
				(island_removal_mode 0)
			)
			(polygon
				(pts
					(xy 385.54914 -82.53476) (xy 385.04114 -82.53476) (xy 385.04114 -82.91576) (xy 385.54914 -82.91576)
				)
			)
		)
	)
	(footprint ""
		(layer "F.Cu")
		(at 383.794 -87.3125 180)
		(property "Reference" "R7D9"
			(at 0 0 180)
			(layer "F.SilkS")
			(hide yes)
			(effects
				(font
					(size 1.27 1.27)
				)
			)
		)
		(property "Value" ""
			(at 0 0 180)
			(layer "F.Fab")
			(effects
				(font
					(size 1.27 1.27)
				)
			)
		)
		(duplicate_pad_numbers_are_jumpers no)
		(fp_poly
			(pts
				(xy -0.2794 -0.1016) (xy 0.2794 -0.1016) (xy 0.2794 0.9906) (xy -0.2794 0.9906)
			)
			(stroke
				(width 0)
				(type default)
			)
			(fill no)
			(layer "F.CrtYd")
		)
		(fp_line
			(start 0.2794 0.9906)
			(end 0.2794 -0.1016)
			(stroke
				(width 0.1)
				(type default)
			)
			(layer "F.Fab")
		)
		(fp_line
			(start 0.2794 -0.1016)
			(end -0.2794 -0.1016)
			(stroke
				(width 0.1)
				(type default)
			)
			(layer "F.Fab")
		)
		(fp_line
			(start -0.2794 0.9906)
			(end 0.2794 0.9906)
			(stroke
				(width 0.1)
				(type default)
			)
			(layer "F.Fab")
		)
		(fp_line
			(start -0.2794 -0.1016)
			(end -0.2794 0.9906)
			(stroke
				(width 0.1)
				(type default)
			)
			(layer "F.Fab")
		)
		(pad "1" smd rect
			(at 0 0 180)
			(size 0.508 0.508)
			(layers "F.Cu" "F.Mask" "F.Paste")
			(net "P3V3_STBY")
		)
		(pad "2" smd rect
			(at 0 0.889 180)
			(size 0.508 0.508)
			(layers "F.Cu" "F.Mask" "F.Paste")
			(net "FM_MB_SLOT_ID1")
		)
		(zone
			(layer "F.Cu")
			(hatch none 0.5)
			(connect_pads
				(clearance 0)
			)
			(min_thickness 0.25)
			(keepout
				(tracks not_allowed)
				(vias allowed)
				(pads allowed)
				(copperpour not_allowed)
				(footprints allowed)
			)
			(placement
				(enabled no)
				(sheetname "")
			)
			(fill
				(thermal_gap 0.5)
				(thermal_bridge_width 0.5)
				(island_removal_mode 0)
			)
			(polygon
				(pts
					(xy 384.048 -87.9475) (xy 383.54 -87.9475) (xy 383.54 -87.5665) (xy 384.048 -87.5665)
				)
			)
		)
		(zone
			(layer "F.Cu")
			(hatch none 0.5)
			(connect_pads
				(clearance 0)
			)
			(min_thickness 0.25)
			(keepout
				(tracks allowed)
				(vias not_allowed)
				(pads allowed)
				(copperpour not_allowed)
				(footprints allowed)
			)
			(placement
				(enabled no)
				(sheetname "")
			)
			(fill
				(thermal_gap 0.5)
				(thermal_bridge_width 0.5)
				(island_removal_mode 0)
			)
			(polygon
				(pts
					(xy 384.048 -87.5665) (xy 383.54 -87.5665) (xy 383.54 -87.9475) (xy 384.048 -87.9475)
				)
			)
		)
	)
)
